(kicad_pcb
	(version 20260206)
	(generator "pcbnew")
	(generator_version "10.0")
	(general
		(thickness 1.6)
		(legacy_teardrops no)
	)
	(paper "A4")
	(title_block
		(title "03242023_DA0F0TMBIJ0_F0T_Motherboard_J_brd_V01_OCP.brd")
		(comment 1 "Grand Teton / footprints 1002-1007 of 6105")
	)
	(layers
		(0 "F.Cu" signal "TOP")
		(4 "In1.Cu" signal "GND")
		(6 "In2.Cu" signal "IN1")
		(8 "In3.Cu" signal "GND1")
		(10 "In4.Cu" signal "IN2")
		(12 "In5.Cu" signal "GND2")
		(14 "In6.Cu" signal "IN3")
		(16 "In7.Cu" signal "GND3")
		(18 "In8.Cu" signal "VCC")
		(20 "In9.Cu" signal "VCC1")
		(22 "In10.Cu" signal "GND4")
		(24 "In11.Cu" signal "IN4")
		(26 "In12.Cu" signal "GND5")
		(28 "In13.Cu" signal "IN5")
		(30 "In14.Cu" signal "GND6")
		(32 "In15.Cu" signal "IN6")
		(34 "In16.Cu" signal "GND7")
		(2 "B.Cu" signal "BOTTOM")
		(9 "F.Adhes" user "F.Adhesive")
		(11 "B.Adhes" user "B.Adhesive")
		(13 "F.Paste" user "Package Geometry/Pastemask Top")
		(15 "B.Paste" user "Package Geometry/Pastemask Bottom")
		(5 "F.SilkS" user "Ref Des/Silkscreen Top")
		(7 "B.SilkS" user "Ref Des/Silkscreen Bottom")
		(1 "F.Mask" user "Board Geometry/Soldermask Top")
		(3 "B.Mask" user "Board Geometry/Soldermask Bottom")
		(17 "Dwgs.User" user "User.Drawings")
		(19 "Cmts.User" user "User.Comments")
		(21 "Eco1.User" user "User.Eco1")
		(23 "Eco2.User" user "User.Eco2")
		(25 "Edge.Cuts" user "Board Geometry/Outline")
		(27 "Margin" user)
		(31 "F.CrtYd" user "Package Geometry/Place Bound Top")
		(29 "B.CrtYd" user "Package Geometry/Place Bound Bottom")
		(35 "F.Fab" user "Ref Des/Assembly Top")
		(33 "B.Fab" user "Ref Des/Assembly Bottom")
	)
	(footprint ""
		(layer "F.Cu")
		(at 348.393004 -360.012996)
		(property "Reference" "R2376"
			(at 0 0 0)
			(layer "F.SilkS")
			(hide yes)
			(effects
				(font
					(size 1.27 1.27)
				)
			)
		)
		(property "Value" ""
			(at 0 0 0)
			(layer "F.Fab")
			(effects
				(font
					(size 1.27 1.27)
				)
			)
		)
		(duplicate_pad_numbers_are_jumpers no)
		(fp_line
			(start -0.7874 -0.4064)
			(end 0.7874 -0.4064)
			(stroke
				(width 0.1524)
				(type default)
			)
			(layer "F.SilkS")
		)
		(fp_line
			(start -0.7874 0.4064)
			(end -0.7874 -0.4064)
			(stroke
				(width 0.1524)
				(type default)
			)
			(layer "F.SilkS")
		)
		(fp_line
			(start 0.7874 -0.4064)
			(end 0.7874 0.4064)
			(stroke
				(width 0.1524)
				(type default)
			)
			(layer "F.SilkS")
		)
		(fp_line
			(start 0.7874 0.4064)
			(end -0.7874 0.4064)
			(stroke
				(width 0.1524)
				(type default)
			)
			(layer "F.SilkS")
		)
		(fp_line
			(start -0.67945 -0.305054)
			(end -0.12065 -0.305054)
			(stroke
				(width 0.1)
				(type default)
			)
			(layer "F.Fab")
		)
		(fp_line
			(start -0.67945 0.3048)
			(end -0.67945 -0.305054)
			(stroke
				(width 0.1)
				(type default)
			)
			(layer "F.Fab")
		)
		(fp_line
			(start -0.12065 -0.305054)
			(end -0.12065 -0.2794)
			(stroke
				(width 0.1)
				(type default)
			)
			(layer "F.Fab")
		)
		(fp_line
			(start -0.12065 -0.2794)
			(end 0.12065 -0.2794)
			(stroke
				(width 0.1)
				(type default)
			)
			(layer "F.Fab")
		)
		(fp_line
			(start -0.12065 0.2794)
			(end -0.12065 0.3048)
			(stroke
				(width 0.1)
				(type default)
			)
			(layer "F.Fab")
		)
		(fp_line
			(start -0.12065 0.3048)
			(end -0.67945 0.3048)
			(stroke
				(width 0.1)
				(type default)
			)
			(layer "F.Fab")
		)
		(fp_line
			(start 0.120396 0.2794)
			(end -0.12065 0.2794)
			(stroke
				(width 0.1)
				(type default)
			)
			(layer "F.Fab")
		)
		(fp_line
			(start 0.120396 0.3048)
			(end 0.120396 0.2794)
			(stroke
				(width 0.1)
				(type default)
			)
			(layer "F.Fab")
		)
		(fp_line
			(start 0.12065 -0.3048)
			(end 0.67945 -0.3048)
			(stroke
				(width 0.1)
				(type default)
			)
			(layer "F.Fab")
		)
		(fp_line
			(start 0.12065 -0.2794)
			(end 0.12065 -0.3048)
			(stroke
				(width 0.1)
				(type default)
			)
			(layer "F.Fab")
		)
		(fp_line
			(start 0.67945 -0.3048)
			(end 0.67945 0.3048)
			(stroke
				(width 0.1)
				(type default)
			)
			(layer "F.Fab")
		)
		(fp_line
			(start 0.67945 0.3048)
			(end 0.120396 0.3048)
			(stroke
				(width 0.1)
				(type default)
			)
			(layer "F.Fab")
		)
		(pad "1" smd circle
			(at -0.40005 0)
			(size 0 0)
			(layers "F.Cu" "F.Mask" "F.Paste")
			(net "IRQ_PSYS_CRIT_N")
		)
		(pad "2" smd circle
			(at 0.40005 0)
			(size 0 0)
			(layers "F.Cu" "F.Mask" "F.Paste")
			(net "PVCCIN_CPU0_PIN_ALERT")
		)
	)
	(footprint ""
		(layer "F.Cu")
		(at 128.45288 -100.167948 -90)
		(property "Reference" "R200"
			(at 0 0 270)
			(layer "F.SilkS")
			(hide yes)
			(effects
				(font
					(size 1.27 1.27)
				)
			)
		)
		(property "Value" ""
			(at 0 0 270)
			(layer "F.Fab")
			(effects
				(font
					(size 1.27 1.27)
				)
			)
		)
		(duplicate_pad_numbers_are_jumpers no)
		(fp_line
			(start -0.7874 0.4064)
			(end -0.7874 -0.4064)
			(stroke
				(width 0.1524)
				(type default)
			)
			(layer "F.SilkS")
		)
		(fp_line
			(start 0.7874 0.4064)
			(end -0.7874 0.4064)
			(stroke
				(width 0.1524)
				(type default)
			)
			(layer "F.SilkS")
		)
		(fp_line
			(start -0.7874 -0.4064)
			(end 0.7874 -0.4064)
			(stroke
				(width 0.1524)
				(type default)
			)
			(layer "F.SilkS")
		)
		(fp_line
			(start 0.7874 -0.4064)
			(end 0.7874 0.4064)
			(stroke
				(width 0.1524)
				(type default)
			)
			(layer "F.SilkS")
		)
		(fp_line
			(start -0.67945 0.3048)
			(end -0.67945 -0.305054)
			(stroke
				(width 0.1)
				(type default)
			)
			(layer "F.Fab")
		)
		(fp_line
			(start -0.12065 0.3048)
			(end -0.67945 0.3048)
			(stroke
				(width 0.1)
				(type default)
			)
			(layer "F.Fab")
		)
		(fp_line
			(start 0.120396 0.3048)
			(end 0.120396 0.2794)
			(stroke
				(width 0.1)
				(type default)
			)
			(layer "F.Fab")
		)
		(fp_line
			(start 0.67945 0.3048)
			(end 0.120396 0.3048)
			(stroke
				(width 0.1)
				(type default)
			)
			(layer "F.Fab")
		)
		(fp_line
			(start -0.12065 0.2794)
			(end -0.12065 0.3048)
			(stroke
				(width 0.1)
				(type default)
			)
			(layer "F.Fab")
		)
		(fp_line
			(start 0.120396 0.2794)
			(end -0.12065 0.2794)
			(stroke
				(width 0.1)
				(type default)
			)
			(layer "F.Fab")
		)
		(fp_line
			(start -0.12065 -0.2794)
			(end 0.12065 -0.2794)
			(stroke
				(width 0.1)
				(type default)
			)
			(layer "F.Fab")
		)
		(fp_line
			(start 0.12065 -0.2794)
			(end 0.12065 -0.3048)
			(stroke
				(width 0.1)
				(type default)
			)
			(layer "F.Fab")
		)
		(fp_line
			(start 0.12065 -0.3048)
			(end 0.67945 -0.3048)
			(stroke
				(width 0.1)
				(type default)
			)
			(layer "F.Fab")
		)
		(fp_line
			(start 0.67945 -0.3048)
			(end 0.67945 0.3048)
			(stroke
				(width 0.1)
				(type default)
			)
			(layer "F.Fab")
		)
		(fp_line
			(start -0.67945 -0.305054)
			(end -0.12065 -0.305054)
			(stroke
				(width 0.1)
				(type default)
			)
			(layer "F.Fab")
		)
		(fp_line
			(start -0.12065 -0.305054)
			(end -0.12065 -0.2794)
			(stroke
				(width 0.1)
				(type default)
			)
			(layer "F.Fab")
		)
		(pad "1" smd circle
			(at -0.40005 0 270)
			(size 0 0)
			(layers "F.Cu" "F.Mask" "F.Paste")
			(net "PVNN_TERM_CPU0")
		)
		(pad "2" smd circle
			(at 0.40005 0 270)
			(size 0 0)
			(layers "F.Cu" "F.Mask" "F.Paste")
			(net "H_CPU0_MEMTRIP_LVC1_R_N")
		)
	)
	(footprint ""
		(layer "F.Cu")
		(at 364.50143 -244.03177 90)
		(property "Reference" "C1009"
			(at 0 0 90)
			(layer "F.SilkS")
			(hide yes)
			(effects
				(font
					(size 1.27 1.27)
				)
			)
		)
		(property "Value" ""
			(at 0 0 90)
			(layer "F.Fab")
			(effects
				(font
					(size 1.27 1.27)
				)
			)
		)
		(duplicate_pad_numbers_are_jumpers no)
		(fp_line
			(start 0.7874 -0.4064)
			(end 0.7874 0.4064)
			(stroke
				(width 0.1524)
				(type default)
			)
			(layer "F.SilkS")
		)
		(fp_line
			(start -0.7874 -0.4064)
			(end 0.7874 -0.4064)
			(stroke
				(width 0.1524)
				(type default)
			)
			(layer "F.SilkS")
		)
		(fp_line
			(start 0.7874 0.4064)
			(end -0.7874 0.4064)
			(stroke
				(width 0.1524)
				(type default)
			)
			(layer "F.SilkS")
		)
		(fp_line
			(start -0.7874 0.4064)
			(end -0.7874 -0.4064)
			(stroke
				(width 0.1524)
				(type default)
			)
			(layer "F.SilkS")
		)
		(fp_line
			(start -0.12065 -0.305054)
			(end -0.12065 -0.2794)
			(stroke
				(width 0.1)
				(type default)
			)
			(layer "F.Fab")
		)
		(fp_line
			(start -0.67945 -0.305054)
			(end -0.12065 -0.305054)
			(stroke
				(width 0.1)
				(type default)
			)
			(layer "F.Fab")
		)
		(fp_line
			(start 0.67945 -0.3048)
			(end 0.67945 0.3048)
			(stroke
				(width 0.1)
				(type default)
			)
			(layer "F.Fab")
		)
		(fp_line
			(start 0.12065 -0.3048)
			(end 0.67945 -0.3048)
			(stroke
				(width 0.1)
				(type default)
			)
			(layer "F.Fab")
		)
		(fp_line
			(start 0.12065 -0.2794)
			(end 0.12065 -0.3048)
			(stroke
				(width 0.1)
				(type default)
			)
			(layer "F.Fab")
		)
		(fp_line
			(start -0.12065 -0.2794)
			(end 0.12065 -0.2794)
			(stroke
				(width 0.1)
				(type default)
			)
			(layer "F.Fab")
		)
		(fp_line
			(start 0.120396 0.2794)
			(end -0.12065 0.2794)
			(stroke
				(width 0.1)
				(type default)
			)
			(layer "F.Fab")
		)
		(fp_line
			(start -0.12065 0.2794)
			(end -0.12065 0.3048)
			(stroke
				(width 0.1)
				(type default)
			)
			(layer "F.Fab")
		)
		(fp_line
			(start 0.67945 0.3048)
			(end 0.120396 0.3048)
			(stroke
				(width 0.1)
				(type default)
			)
			(layer "F.Fab")
		)
		(fp_line
			(start 0.120396 0.3048)
			(end 0.120396 0.2794)
			(stroke
				(width 0.1)
				(type default)
			)
			(layer "F.Fab")
		)
		(fp_line
			(start -0.12065 0.3048)
			(end -0.67945 0.3048)
			(stroke
				(width 0.1)
				(type default)
			)
			(layer "F.Fab")
		)
		(fp_line
			(start -0.67945 0.3048)
			(end -0.67945 -0.305054)
			(stroke
				(width 0.1)
				(type default)
			)
			(layer "F.Fab")
		)
		(pad "1" smd circle
			(at -0.40005 0 90)
			(size 0 0)
			(layers "F.Cu" "F.Mask" "F.Paste")
			(net "PVCCIN_CPU0")
		)
		(pad "2" smd circle
			(at 0.40005 0 90)
			(size 0 0)
			(layers "F.Cu" "F.Mask" "F.Paste")
			(net "GND")
		)
	)
	(footprint ""
		(layer "F.Cu")
		(at 218.694 -96.103948 180)
		(property "Reference" "R4620"
			(at 0 0 180)
			(layer "F.SilkS")
			(hide yes)
			(effects
				(font
					(size 1.27 1.27)
				)
			)
		)
		(property "Value" ""
			(at 0 0 180)
			(layer "F.Fab")
			(effects
				(font
					(size 1.27 1.27)
				)
			)
		)
		(duplicate_pad_numbers_are_jumpers no)
		(fp_line
			(start 0.7874 0.4064)
			(end -0.7874 0.4064)
			(stroke
				(width 0.1524)
				(type default)
			)
			(layer "F.SilkS")
		)
		(fp_line
			(start 0.7874 -0.4064)
			(end 0.7874 0.4064)
			(stroke
				(width 0.1524)
				(type default)
			)
			(layer "F.SilkS")
		)
		(fp_line
			(start -0.7874 0.4064)
			(end -0.7874 -0.4064)
			(stroke
				(width 0.1524)
				(type default)
			)
			(layer "F.SilkS")
		)
		(fp_line
			(start -0.7874 -0.4064)
			(end 0.7874 -0.4064)
			(stroke
				(width 0.1524)
				(type default)
			)
			(layer "F.SilkS")
		)
		(fp_line
			(start 0.67945 0.3048)
			(end 0.120396 0.3048)
			(stroke
				(width 0.1)
				(type default)
			)
			(layer "F.Fab")
		)
		(fp_line
			(start 0.67945 -0.3048)
			(end 0.67945 0.3048)
			(stroke
				(width 0.1)
				(type default)
			)
			(layer "F.Fab")
		)
		(fp_line
			(start 0.12065 -0.2794)
			(end 0.12065 -0.3048)
			(stroke
				(width 0.1)
				(type default)
			)
			(layer "F.Fab")
		)
		(fp_line
			(start 0.12065 -0.3048)
			(end 0.67945 -0.3048)
			(stroke
				(width 0.1)
				(type default)
			)
			(layer "F.Fab")
		)
		(fp_line
			(start 0.120396 0.3048)
			(end 0.120396 0.2794)
			(stroke
				(width 0.1)
				(type default)
			)
			(layer "F.Fab")
		)
		(fp_line
			(start 0.120396 0.2794)
			(end -0.12065 0.2794)
			(stroke
				(width 0.1)
				(type default)
			)
			(layer "F.Fab")
		)
		(fp_line
			(start -0.12065 0.3048)
			(end -0.67945 0.3048)
			(stroke
				(width 0.1)
				(type default)
			)
			(layer "F.Fab")
		)
		(fp_line
			(start -0.12065 0.2794)
			(end -0.12065 0.3048)
			(stroke
				(width 0.1)
				(type default)
			)
			(layer "F.Fab")
		)
		(fp_line
			(start -0.12065 -0.2794)
			(end 0.12065 -0.2794)
			(stroke
				(width 0.1)
				(type default)
			)
			(layer "F.Fab")
		)
		(fp_line
			(start -0.12065 -0.305054)
			(end -0.12065 -0.2794)
			(stroke
				(width 0.1)
				(type default)
			)
			(layer "F.Fab")
		)
		(fp_line
			(start -0.67945 0.3048)
			(end -0.67945 -0.305054)
			(stroke
				(width 0.1)
				(type default)
			)
			(layer "F.Fab")
		)
		(fp_line
			(start -0.67945 -0.305054)
			(end -0.12065 -0.305054)
			(stroke
				(width 0.1)
				(type default)
			)
			(layer "F.Fab")
		)
		(pad "1" smd circle
			(at -0.40005 0 180)
			(size 0 0)
			(layers "F.Cu" "F.Mask" "F.Paste")
			(net "P3V3_AUX")
		)
		(pad "2" smd circle
			(at 0.40005 0 180)
			(size 0 0)
			(layers "F.Cu" "F.Mask" "F.Paste")
			(net "IRQ_UV_DETECT_N")
		)
	)
	(footprint ""
		(layer "F.Cu")
		(at 220.087444 -102.255574 180)
		(property "Reference" "R2230"
			(at 0 0 180)
			(layer "F.SilkS")
			(hide yes)
			(effects
				(font
					(size 1.27 1.27)
				)
			)
		)
		(property "Value" ""
			(at 0 0 180)
			(layer "F.Fab")
			(effects
				(font
					(size 1.27 1.27)
				)
			)
		)
		(duplicate_pad_numbers_are_jumpers no)
		(fp_line
			(start 0.7874 0.4064)
			(end -0.7874 0.4064)
			(stroke
				(width 0.1524)
				(type default)
			)
			(layer "F.SilkS")
		)
		(fp_line
			(start 0.7874 -0.4064)
			(end 0.7874 0.4064)
			(stroke
				(width 0.1524)
				(type default)
			)
			(layer "F.SilkS")
		)
		(fp_line
			(start -0.7874 0.4064)
			(end -0.7874 -0.4064)
			(stroke
				(width 0.1524)
				(type default)
			)
			(layer "F.SilkS")
		)
		(fp_line
			(start -0.7874 -0.4064)
			(end 0.7874 -0.4064)
			(stroke
				(width 0.1524)
				(type default)
			)
			(layer "F.SilkS")
		)
		(fp_line
			(start 0.67945 0.3048)
			(end 0.120396 0.3048)
			(stroke
				(width 0.1)
				(type default)
			)
			(layer "F.Fab")
		)
		(fp_line
			(start 0.67945 -0.3048)
			(end 0.67945 0.3048)
			(stroke
				(width 0.1)
				(type default)
			)
			(layer "F.Fab")
		)
		(fp_line
			(start 0.12065 -0.2794)
			(end 0.12065 -0.3048)
			(stroke
				(width 0.1)
				(type default)
			)
			(layer "F.Fab")
		)
		(fp_line
			(start 0.12065 -0.3048)
			(end 0.67945 -0.3048)
			(stroke
				(width 0.1)
				(type default)
			)
			(layer "F.Fab")
		)
		(fp_line
			(start 0.120396 0.3048)
			(end 0.120396 0.2794)
			(stroke
				(width 0.1)
				(type default)
			)
			(layer "F.Fab")
		)
		(fp_line
			(start 0.120396 0.2794)
			(end -0.12065 0.2794)
			(stroke
				(width 0.1)
				(type default)
			)
			(layer "F.Fab")
		)
		(fp_line
			(start -0.12065 0.3048)
			(end -0.67945 0.3048)
			(stroke
				(width 0.1)
				(type default)
			)
			(layer "F.Fab")
		)
		(fp_line
			(start -0.12065 0.2794)
			(end -0.12065 0.3048)
			(stroke
				(width 0.1)
				(type default)
			)
			(layer "F.Fab")
		)
		(fp_line
			(start -0.12065 -0.2794)
			(end 0.12065 -0.2794)
			(stroke
				(width 0.1)
				(type default)
			)
			(layer "F.Fab")
		)
		(fp_line
			(start -0.12065 -0.305054)
			(end -0.12065 -0.2794)
			(stroke
				(width 0.1)
				(type default)
			)
			(layer "F.Fab")
		)
		(fp_line
			(start -0.67945 0.3048)
			(end -0.67945 -0.305054)
			(stroke
				(width 0.1)
				(type default)
			)
			(layer "F.Fab")
		)
		(fp_line
			(start -0.67945 -0.305054)
			(end -0.12065 -0.305054)
			(stroke
				(width 0.1)
				(type default)
			)
			(layer "F.Fab")
		)
		(pad "1" smd circle
			(at -0.40005 0 180)
			(size 0 0)
			(layers "F.Cu" "F.Mask" "F.Paste")
			(net "P3V3_AUX")
		)
		(pad "2" smd circle
			(at 0.40005 0 180)
			(size 0 0)
			(layers "F.Cu" "F.Mask" "F.Paste")
			(net "A_P12V_STBY_FPH_GATE")
		)
	)
	(footprint ""
		(layer "F.Cu")
		(at 450.43725 -44.171362 180)
		(property "Reference" "R3501"
			(at 0 0 180)
			(layer "F.SilkS")
			(hide yes)
			(effects
				(font
					(size 1.27 1.27)
				)
			)
		)
		(property "Value" ""
			(at 0 0 180)
			(layer "F.Fab")
			(effects
				(font
					(size 1.27 1.27)
				)
			)
		)
		(duplicate_pad_numbers_are_jumpers no)
		(fp_line
			(start 0.7874 0.4064)
			(end -0.7874 0.4064)
			(stroke
				(width 0.1524)
				(type default)
			)
			(layer "F.SilkS")
		)
		(fp_line
			(start 0.7874 -0.4064)
			(end 0.7874 0.4064)
			(stroke
				(width 0.1524)
				(type default)
			)
			(layer "F.SilkS")
		)
		(fp_line
			(start -0.7874 0.4064)
			(end -0.7874 -0.4064)
			(stroke
				(width 0.1524)
				(type default)
			)
			(layer "F.SilkS")
		)
		(fp_line
			(start -0.7874 -0.4064)
			(end 0.7874 -0.4064)
			(stroke
				(width 0.1524)
				(type default)
			)
			(layer "F.SilkS")
		)
		(fp_line
			(start 0.67945 0.3048)
			(end 0.120396 0.3048)
			(stroke
				(width 0.1)
				(type default)
			)
			(layer "F.Fab")
		)
		(fp_line
			(start 0.67945 -0.3048)
			(end 0.67945 0.3048)
			(stroke
				(width 0.1)
				(type default)
			)
			(layer "F.Fab")
		)
		(fp_line
			(start 0.12065 -0.2794)
			(end 0.12065 -0.3048)
			(stroke
				(width 0.1)
				(type default)
			)
			(layer "F.Fab")
		)
		(fp_line
			(start 0.12065 -0.3048)
			(end 0.67945 -0.3048)
			(stroke
				(width 0.1)
				(type default)
			)
			(layer "F.Fab")
		)
		(fp_line
			(start 0.120396 0.3048)
			(end 0.120396 0.2794)
			(stroke
				(width 0.1)
				(type default)
			)
			(layer "F.Fab")
		)
		(fp_line
			(start 0.120396 0.2794)
			(end -0.12065 0.2794)
			(stroke
				(width 0.1)
				(type default)
			)
			(layer "F.Fab")
		)
		(fp_line
			(start -0.12065 0.3048)
			(end -0.67945 0.3048)
			(stroke
				(width 0.1)
				(type default)
			)
			(layer "F.Fab")
		)
		(fp_line
			(start -0.12065 0.2794)
			(end -0.12065 0.3048)
			(stroke
				(width 0.1)
				(type default)
			)
			(layer "F.Fab")
		)
		(fp_line
			(start -0.12065 -0.2794)
			(end 0.12065 -0.2794)
			(stroke
				(width 0.1)
				(type default)
			)
			(layer "F.Fab")
		)
		(fp_line
			(start -0.12065 -0.305054)
			(end -0.12065 -0.2794)
			(stroke
				(width 0.1)
				(type default)
			)
			(layer "F.Fab")
		)
		(fp_line
			(start -0.67945 0.3048)
			(end -0.67945 -0.305054)
			(stroke
				(width 0.1)
				(type default)
			)
			(layer "F.Fab")
		)
		(fp_line
			(start -0.67945 -0.305054)
			(end -0.12065 -0.305054)
			(stroke
				(width 0.1)
				(type default)
			)
			(layer "F.Fab")
		)
		(pad "1" smd circle
			(at -0.40005 0 180)
			(size 0 0)
			(layers "F.Cu" "F.Mask" "F.Paste")
			(net "P3V3_OCP_SFF")
		)
		(pad "2" smd circle
			(at 0.40005 0 180)
			(size 0 0)
			(layers "F.Cu" "F.Mask" "F.Paste")
			(net "SMB_OCP_SFF_3V3AUX_BUF_SDA")
		)
	)
)
